;LEADER: 12 
;HEADER: 
;CODE  : ASCII 
;FILE  : 9127_F0T_Expander_BD_F_v02_0110_1240-bd-1-11.drl for backdrilling ... from layer TOP to layer GND4
;DESIGN: 9127_F0T_Expander_BD_F_v02_0110_1240.brd
;MUST-NOT-CUT-LAYER = IN4,  MAX_DRILL_DEPTH = 78.75 MILS,  MFG_STUB_LENGTH = 0.00 MILS
;   BackdrillSize 1. = 17.700000 Tolerance = +0.000000/-0.000000 NON_PLATED MILS Quantity = 8
%
G90
X1297687Y-0043656
X1297687Y-0040256
X1337687Y-0082706
X1337687Y-0079306
X1517261Y-0043758
X1517261Y-0040358
X1481905Y-0082678
X1481905Y-0079278
M30
